(kicad_pcb
	(version 20260206)
	(generator "pcbnew")
	(generator_version "10.0")
	(general
		(thickness 1.6)
		(legacy_teardrops no)
	)
	(paper "A4")
	(title_block
		(title "dpb — 14545-sa.0730WZS0815.brd")
		(comment 1 "Honey Badger (Wiwynn) / footprints 903-909 of 1066")
	)
	(layers
		(0 "F.Cu" signal "TOP")
		(4 "In1.Cu" signal "L2GND")
		(6 "In2.Cu" signal "L3")
		(8 "In3.Cu" signal "L4VCC")
		(10 "In4.Cu" signal "L5VCC")
		(12 "In5.Cu" signal "L6")
		(14 "In6.Cu" signal "L7GND")
		(2 "B.Cu" signal "BOTTOM")
		(9 "F.Adhes" user "F.Adhesive")
		(11 "B.Adhes" user "B.Adhesive")
		(13 "F.Paste" user "Package Geometry/Pastemask Top")
		(15 "B.Paste" user "Package Geometry/Pastemask Bottom")
		(5 "F.SilkS" user "Ref Des/Silkscreen Top")
		(7 "B.SilkS" user "Ref Des/Silkscreen Bottom")
		(1 "F.Mask" user "Board Geometry/Soldermask Top")
		(3 "B.Mask" user "Board Geometry/Soldermask Bottom")
		(17 "Dwgs.User" user "User.Drawings")
		(19 "Cmts.User" user "User.Comments")
		(21 "Eco1.User" user "User.Eco1")
		(23 "Eco2.User" user "User.Eco2")
		(25 "Edge.Cuts" user "Board Geometry/Outline")
		(27 "Margin" user)
		(31 "F.CrtYd" user "Package Geometry/Place Bound Top")
		(29 "B.CrtYd" user "Package Geometry/Place Bound Bottom")
		(35 "F.Fab" user "Ref Des/Assembly Top")
		(33 "B.Fab" user "Ref Des/Assembly Bottom")
	)
	(footprint ""
		(layer "F.Cu")
		(at 58.166 -396.9004 180)
		(property "Reference" "C209"
			(at 0 0 180)
			(layer "F.SilkS")
			(hide yes)
			(effects
				(font
					(size 1.27 1.27)
				)
			)
		)
		(property "Value" "SC10U25V6KX-1GP"
			(at -0.0762 -5.1308 180)
			(unlocked yes)
			(layer "F.Fab")
			(hide yes)
			(effects
				(font
					(size 1.016 1.016)
					(thickness 0.1524)
				)
			)
		)
		(property "Device Type" "C1206H71"
			(at -0.127 -6.6548 180)
			(unlocked yes)
			(layer "F.Fab")
			(hide yes)
			(effects
				(font
					(size 1.016 1.016)
					(thickness 0.1524)
				)
			)
		)
		(duplicate_pad_numbers_are_jumpers no)
		(fp_line
			(start 1.016 2.2352)
			(end -1.016 2.2352)
			(stroke
				(width 0.1524)
				(type default)
			)
			(layer "F.SilkS")
		)
		(fp_line
			(start 1.016 0.8382)
			(end 1.016 2.2352)
			(stroke
				(width 0.1524)
				(type default)
			)
			(layer "F.SilkS")
		)
		(fp_line
			(start 1.016 -2.2352)
			(end 1.016 -0.8382)
			(stroke
				(width 0.1524)
				(type default)
			)
			(layer "F.SilkS")
		)
		(fp_line
			(start -1.016 2.2352)
			(end -1.016 0.8382)
			(stroke
				(width 0.1524)
				(type default)
			)
			(layer "F.SilkS")
		)
		(fp_line
			(start -1.016 -0.8382)
			(end -1.016 -2.2352)
			(stroke
				(width 0.1524)
				(type default)
			)
			(layer "F.SilkS")
		)
		(fp_line
			(start -1.016 -2.2352)
			(end 1.016 -2.2352)
			(stroke
				(width 0.1524)
				(type default)
			)
			(layer "F.SilkS")
		)
		(fp_rect
			(start -1.0922 2.3114)
			(end 1.0922 -2.3114)
			(stroke
				(width 0)
				(type default)
			)
			(fill no)
			(layer "F.CrtYd")
		)
		(fp_poly
			(pts
				(xy 1.0922 -2.3114) (xy 1.0922 2.3114) (xy -1.0922 2.3114) (xy -1.0922 -2.3114)
			)
			(stroke
				(width 0)
				(type default)
			)
			(fill no)
			(layer "F.Fab")
		)
		(pad "1" smd rect
			(at 0 -1.397 180)
			(size 1.651 1.27)
			(layers "F.Cu" "F.Mask" "F.Paste")
			(net "P12V_HDD6")
		)
		(pad "2" smd rect
			(at 0 1.397 180)
			(size 1.651 1.27)
			(layers "F.Cu" "F.Mask" "F.Paste")
			(net "GND")
		)
	)
	(footprint ""
		(layer "F.Cu")
		(at 43.815 -429.5648 -90)
		(property "Reference" "R397"
			(at 0 0 270)
			(layer "F.SilkS")
			(hide yes)
			(effects
				(font
					(size 1.27 1.27)
				)
			)
		)
		(property "Value" "10KR2F-2-GP"
			(at 0.064008 -3.993896 270)
			(unlocked yes)
			(layer "F.Fab")
			(hide yes)
			(effects
				(font
					(size 1.016 1.016)
					(thickness 0.1524)
				)
			)
		)
		(property "Device Type" "R402H16"
			(at 0.064008 -5.517896 270)
			(unlocked yes)
			(layer "F.Fab")
			(hide yes)
			(effects
				(font
					(size 1.016 1.016)
					(thickness 0.1524)
				)
			)
		)
		(duplicate_pad_numbers_are_jumpers no)
		(fp_line
			(start -0.508 -0.9398)
			(end -0.508 0.9398)
			(stroke
				(width 0.1524)
				(type default)
			)
			(layer "F.SilkS")
		)
		(fp_line
			(start 0.508 -0.9398)
			(end -0.508 -0.9398)
			(stroke
				(width 0.1524)
				(type default)
			)
			(layer "F.SilkS")
		)
		(fp_rect
			(start -0.508 0.9398)
			(end 0.508 -0.9398)
			(stroke
				(width 0)
				(type default)
			)
			(fill no)
			(layer "F.CrtYd")
		)
		(fp_rect
			(start -0.508 0.9398)
			(end 0.508 -0.9398)
			(stroke
				(width 0)
				(type default)
			)
			(fill no)
			(layer "F.Fab")
		)
		(pad "1" smd custom
			(at 0 -0.4445 270)
			(size 0.1397 0.1397)
			(layers "F.Cu" "F.Mask" "F.Paste")
			(net "P12V")
			(options
				(clearance outline)
				(anchor circle)
			)
			(primitives
				(gr_poly
					(pts
						(arc
							(start -0.1778 -0.2794)
							(mid -0.249642 -0.249642)
							(end -0.2794 -0.1778)
						)
						(arc
							(start -0.2794 0.1778)
							(mid -0.249642 0.249642)
							(end -0.1778 0.2794)
						)
						(arc
							(start 0.1778 0.2794)
							(mid 0.249642 0.249642)
							(end 0.2794 0.1778)
						)
						(arc
							(start 0.2794 -0.1778)
							(mid 0.249642 -0.249642)
							(end 0.1778 -0.2794)
						)
					)
					(width 0)
					(fill yes)
				)
			)
		)
		(pad "2" smd custom
			(at 0 0.4445 270)
			(size 0.1397 0.1397)
			(layers "F.Cu" "F.Mask" "F.Paste")
			(net "HDD10_LED_G")
			(options
				(clearance outline)
				(anchor circle)
			)
			(primitives
				(gr_poly
					(pts
						(arc
							(start -0.1778 -0.2794)
							(mid -0.249642 -0.249642)
							(end -0.2794 -0.1778)
						)
						(arc
							(start -0.2794 0.1778)
							(mid -0.249642 0.249642)
							(end -0.1778 0.2794)
						)
						(arc
							(start 0.1778 0.2794)
							(mid 0.249642 0.249642)
							(end 0.2794 0.1778)
						)
						(arc
							(start 0.2794 -0.1778)
							(mid 0.249642 -0.249642)
							(end 0.1778 -0.2794)
						)
					)
					(width 0)
					(fill yes)
				)
			)
		)
	)
	(footprint ""
		(layer "F.Cu")
		(at 50.0634 -209.042 90)
		(property "Reference" "R420"
			(at 0 0 90)
			(layer "F.SilkS")
			(hide yes)
			(effects
				(font
					(size 1.27 1.27)
				)
			)
		)
		(property "Value" "0R2J-2-GP"
			(at 0.064008 -3.993896 90)
			(unlocked yes)
			(layer "F.Fab")
			(hide yes)
			(effects
				(font
					(size 1.016 1.016)
					(thickness 0.1524)
				)
			)
		)
		(property "Device Type" "R402H16"
			(at 0.064008 -5.517896 90)
			(unlocked yes)
			(layer "F.Fab")
			(hide yes)
			(effects
				(font
					(size 1.016 1.016)
					(thickness 0.1524)
				)
			)
		)
		(duplicate_pad_numbers_are_jumpers no)
		(fp_line
			(start 0.508 -0.9398)
			(end -0.508 -0.9398)
			(stroke
				(width 0.1524)
				(type default)
			)
			(layer "F.SilkS")
		)
		(fp_line
			(start -0.508 -0.9398)
			(end -0.508 0.9398)
			(stroke
				(width 0.1524)
				(type default)
			)
			(layer "F.SilkS")
		)
		(fp_rect
			(start -0.508 0.9398)
			(end 0.508 -0.9398)
			(stroke
				(width 0)
				(type default)
			)
			(fill no)
			(layer "F.CrtYd")
		)
		(fp_rect
			(start -0.508 0.9398)
			(end 0.508 -0.9398)
			(stroke
				(width 0)
				(type default)
			)
			(fill no)
			(layer "F.Fab")
		)
		(pad "1" smd custom
			(at 0 -0.4445 90)
			(size 0.1397 0.1397)
			(layers "F.Cu" "F.Mask" "F.Paste")
			(net "SW_HDD12_G")
			(options
				(clearance outline)
				(anchor circle)
			)
			(primitives
				(gr_poly
					(pts
						(arc
							(start -0.1778 -0.2794)
							(mid -0.249642 -0.249642)
							(end -0.2794 -0.1778)
						)
						(arc
							(start -0.2794 0.1778)
							(mid -0.249642 0.249642)
							(end -0.1778 0.2794)
						)
						(arc
							(start 0.1778 0.2794)
							(mid 0.249642 0.249642)
							(end 0.2794 0.1778)
						)
						(arc
							(start 0.2794 -0.1778)
							(mid 0.249642 -0.249642)
							(end 0.1778 -0.2794)
						)
					)
					(width 0)
					(fill yes)
				)
			)
		)
		(pad "2" smd custom
			(at 0 0.4445 90)
			(size 0.1397 0.1397)
			(layers "F.Cu" "F.Mask" "F.Paste")
			(net "SW_HDD12_R")
			(options
				(clearance outline)
				(anchor circle)
			)
			(primitives
				(gr_poly
					(pts
						(arc
							(start -0.1778 -0.2794)
							(mid -0.249642 -0.249642)
							(end -0.2794 -0.1778)
						)
						(arc
							(start -0.2794 0.1778)
							(mid -0.249642 0.249642)
							(end -0.1778 0.2794)
						)
						(arc
							(start 0.1778 0.2794)
							(mid 0.249642 0.249642)
							(end 0.2794 0.1778)
						)
						(arc
							(start 0.2794 -0.1778)
							(mid 0.249642 -0.249642)
							(end 0.1778 -0.2794)
						)
					)
					(width 0)
					(fill yes)
				)
			)
		)
	)
	(footprint ""
		(layer "F.Cu")
		(at 215.195912 -73.691496 -90)
		(property "Reference" "R161"
			(at 0 0 270)
			(layer "F.SilkS")
			(hide yes)
			(effects
				(font
					(size 1.27 1.27)
				)
			)
		)
		(property "Value" "2R2010J-1-GP"
			(at 0.254 -8.0772 270)
			(unlocked yes)
			(layer "F.Fab")
			(hide yes)
			(effects
				(font
					(size 1.016 1.016)
					(thickness 0.1524)
				)
			)
		)
		(property "Device Type" "R2010H28"
			(at 0.254 -9.6774 270)
			(unlocked yes)
			(layer "F.Fab")
			(hide yes)
			(effects
				(font
					(size 1.016 1.016)
					(thickness 0.1524)
				)
			)
		)
		(duplicate_pad_numbers_are_jumpers no)
		(fp_line
			(start -1.651 3.302)
			(end 1.651 3.302)
			(stroke
				(width 0.1524)
				(type default)
			)
			(layer "F.SilkS")
		)
		(fp_line
			(start 1.651 3.302)
			(end 1.651 -3.302)
			(stroke
				(width 0.1524)
				(type default)
			)
			(layer "F.SilkS")
		)
		(fp_line
			(start -1.651 -3.302)
			(end -1.651 3.302)
			(stroke
				(width 0.1524)
				(type default)
			)
			(layer "F.SilkS")
		)
		(fp_line
			(start 1.651 -3.302)
			(end -1.651 -3.302)
			(stroke
				(width 0.1524)
				(type default)
			)
			(layer "F.SilkS")
		)
		(fp_rect
			(start -1.7272 -3.3782)
			(end 1.7272 3.3782)
			(stroke
				(width 0)
				(type default)
			)
			(fill no)
			(layer "F.CrtYd")
		)
		(fp_poly
			(pts
				(xy 1.7272 3.3782) (xy 1.7272 -3.3782) (xy -1.7272 -3.3782) (xy -1.7272 3.3782)
			)
			(stroke
				(width 0)
				(type default)
			)
			(fill no)
			(layer "F.Fab")
		)
		(pad "1" smd rect
			(at 0 -2.3495 270)
			(size 2.794 1.143)
			(layers "F.Cu" "F.Mask" "F.Paste")
			(net "5V_PRE_4")
		)
		(pad "2" smd rect
			(at 0 2.3495 270)
			(size 2.794 1.143)
			(layers "F.Cu" "F.Mask" "F.Paste")
			(net "P5V_HDD4")
		)
	)
	(footprint ""
		(layer "F.Cu")
		(at 27.812746 -304.828702 180)
		(property "Reference" "R466"
			(at 0 0 180)
			(layer "F.SilkS")
			(hide yes)
			(effects
				(font
					(size 1.27 1.27)
				)
			)
		)
		(property "Value" "4K7R2J-2-GP"
			(at 0.064008 -3.993896 180)
			(unlocked yes)
			(layer "F.Fab")
			(hide yes)
			(effects
				(font
					(size 1.016 1.016)
					(thickness 0.1524)
				)
			)
		)
		(property "Device Type" "R402H16"
			(at 0.064008 -5.517896 180)
			(unlocked yes)
			(layer "F.Fab")
			(hide yes)
			(effects
				(font
					(size 1.016 1.016)
					(thickness 0.1524)
				)
			)
		)
		(duplicate_pad_numbers_are_jumpers no)
		(fp_line
			(start 0.508 -0.9398)
			(end -0.508 -0.9398)
			(stroke
				(width 0.1524)
				(type default)
			)
			(layer "F.SilkS")
		)
		(fp_line
			(start -0.508 -0.9398)
			(end -0.508 0.9398)
			(stroke
				(width 0.1524)
				(type default)
			)
			(layer "F.SilkS")
		)
		(fp_rect
			(start -0.508 0.9398)
			(end 0.508 -0.9398)
			(stroke
				(width 0)
				(type default)
			)
			(fill no)
			(layer "F.CrtYd")
		)
		(fp_rect
			(start -0.508 0.9398)
			(end 0.508 -0.9398)
			(stroke
				(width 0)
				(type default)
			)
			(fill no)
			(layer "F.Fab")
		)
		(pad "1" smd custom
			(at 0 -0.4445 180)
			(size 0.1397 0.1397)
			(layers "F.Cu" "F.Mask" "F.Paste")
			(net "P3V3")
			(options
				(clearance outline)
				(anchor circle)
			)
			(primitives
				(gr_poly
					(pts
						(arc
							(start -0.1778 -0.2794)
							(mid -0.249642 -0.249642)
							(end -0.2794 -0.1778)
						)
						(arc
							(start -0.2794 0.1778)
							(mid -0.249642 0.249642)
							(end -0.1778 0.2794)
						)
						(arc
							(start 0.1778 0.2794)
							(mid 0.249642 0.249642)
							(end 0.2794 0.1778)
						)
						(arc
							(start 0.2794 -0.1778)
							(mid 0.249642 -0.249642)
							(end 0.1778 -0.2794)
						)
					)
					(width 0)
					(fill yes)
				)
			)
		)
		(pad "2" smd custom
			(at 0 0.4445 180)
			(size 0.1397 0.1397)
			(layers "F.Cu" "F.Mask" "F.Paste")
			(net "SAS_EXP_A_PWR11")
			(options
				(clearance outline)
				(anchor circle)
			)
			(primitives
				(gr_poly
					(pts
						(arc
							(start -0.1778 -0.2794)
							(mid -0.249642 -0.249642)
							(end -0.2794 -0.1778)
						)
						(arc
							(start -0.2794 0.1778)
							(mid -0.249642 0.249642)
							(end -0.1778 0.2794)
						)
						(arc
							(start 0.1778 0.2794)
							(mid 0.249642 0.249642)
							(end 0.2794 0.1778)
						)
						(arc
							(start 0.2794 -0.1778)
							(mid 0.249642 -0.249642)
							(end 0.1778 -0.2794)
						)
					)
					(width 0)
					(fill yes)
				)
			)
		)
	)
	(footprint ""
		(layer "F.Cu")
		(at 194.564 -191.262 180)
		(property "Reference" "R566"
			(at 0 0 180)
			(layer "F.SilkS")
			(hide yes)
			(effects
				(font
					(size 1.27 1.27)
				)
			)
		)
		(property "Value" "300KR2F-GP"
			(at 0.064008 -3.993896 180)
			(unlocked yes)
			(layer "F.Fab")
			(hide yes)
			(effects
				(font
					(size 1.016 1.016)
					(thickness 0.1524)
				)
			)
		)
		(property "Device Type" "R402H16"
			(at 0.064008 -5.517896 180)
			(unlocked yes)
			(layer "F.Fab")
			(hide yes)
			(effects
				(font
					(size 1.016 1.016)
					(thickness 0.1524)
				)
			)
		)
		(duplicate_pad_numbers_are_jumpers no)
		(fp_line
			(start 0.508 -0.9398)
			(end -0.508 -0.9398)
			(stroke
				(width 0.1524)
				(type default)
			)
			(layer "F.SilkS")
		)
		(fp_line
			(start -0.508 -0.9398)
			(end -0.508 0.9398)
			(stroke
				(width 0.1524)
				(type default)
			)
			(layer "F.SilkS")
		)
		(fp_rect
			(start -0.508 0.9398)
			(end 0.508 -0.9398)
			(stroke
				(width 0)
				(type default)
			)
			(fill no)
			(layer "F.CrtYd")
		)
		(fp_rect
			(start -0.508 0.9398)
			(end 0.508 -0.9398)
			(stroke
				(width 0)
				(type default)
			)
			(fill no)
			(layer "F.Fab")
		)
		(pad "1" smd custom
			(at 0 -0.4445 180)
			(size 0.1397 0.1397)
			(layers "F.Cu" "F.Mask" "F.Paste")
			(net "SW_HDD3_N")
			(options
				(clearance outline)
				(anchor circle)
			)
			(primitives
				(gr_poly
					(pts
						(arc
							(start -0.1778 -0.2794)
							(mid -0.249642 -0.249642)
							(end -0.2794 -0.1778)
						)
						(arc
							(start -0.2794 0.1778)
							(mid -0.249642 0.249642)
							(end -0.1778 0.2794)
						)
						(arc
							(start 0.1778 0.2794)
							(mid 0.249642 0.249642)
							(end 0.2794 0.1778)
						)
						(arc
							(start 0.2794 -0.1778)
							(mid 0.249642 -0.249642)
							(end 0.1778 -0.2794)
						)
					)
					(width 0)
					(fill yes)
				)
			)
		)
		(pad "2" smd custom
			(at 0 0.4445 180)
			(size 0.1397 0.1397)
			(layers "F.Cu" "F.Mask" "F.Paste")
			(net "P12V")
			(options
				(clearance outline)
				(anchor circle)
			)
			(primitives
				(gr_poly
					(pts
						(arc
							(start -0.1778 -0.2794)
							(mid -0.249642 -0.249642)
							(end -0.2794 -0.1778)
						)
						(arc
							(start -0.2794 0.1778)
							(mid -0.249642 0.249642)
							(end -0.1778 0.2794)
						)
						(arc
							(start 0.1778 0.2794)
							(mid 0.249642 0.249642)
							(end 0.2794 0.1778)
						)
						(arc
							(start 0.2794 -0.1778)
							(mid 0.249642 -0.249642)
							(end 0.1778 -0.2794)
						)
					)
					(width 0)
					(fill yes)
				)
			)
		)
	)
	(footprint ""
		(layer "F.Cu")
		(at 207.136746 -462.6737 90)
		(property "Reference" "R334"
			(at 0 0 90)
			(layer "F.SilkS")
			(hide yes)
			(effects
				(font
					(size 1.27 1.27)
				)
			)
		)
		(property "Value" "0R2J-2-GP"
			(at 0.064008 -3.993896 90)
			(unlocked yes)
			(layer "F.Fab")
			(hide yes)
			(effects
				(font
					(size 1.016 1.016)
					(thickness 0.1524)
				)
			)
		)
		(property "Device Type" "R402H16"
			(at 0.064008 -5.517896 90)
			(unlocked yes)
			(layer "F.Fab")
			(hide yes)
			(effects
				(font
					(size 1.016 1.016)
					(thickness 0.1524)
				)
			)
		)
		(duplicate_pad_numbers_are_jumpers no)
		(fp_line
			(start 0.508 -0.9398)
			(end -0.508 -0.9398)
			(stroke
				(width 0.1524)
				(type default)
			)
			(layer "F.SilkS")
		)
		(fp_line
			(start -0.508 -0.9398)
			(end -0.508 0.9398)
			(stroke
				(width 0.1524)
				(type default)
			)
			(layer "F.SilkS")
		)
		(fp_rect
			(start -0.508 0.9398)
			(end 0.508 -0.9398)
			(stroke
				(width 0)
				(type default)
			)
			(fill no)
			(layer "F.CrtYd")
		)
		(fp_rect
			(start -0.508 0.9398)
			(end 0.508 -0.9398)
			(stroke
				(width 0)
				(type default)
			)
			(fill no)
			(layer "F.Fab")
		)
		(pad "1" smd custom
			(at 0 -0.4445 90)
			(size 0.1397 0.1397)
			(layers "F.Cu" "F.Mask" "F.Paste")
			(net "I2C_B_SCL")
			(options
				(clearance outline)
				(anchor circle)
			)
			(primitives
				(gr_poly
					(pts
						(arc
							(start -0.1778 -0.2794)
							(mid -0.249642 -0.249642)
							(end -0.2794 -0.1778)
						)
						(arc
							(start -0.2794 0.1778)
							(mid -0.249642 0.249642)
							(end -0.1778 0.2794)
						)
						(arc
							(start 0.1778 0.2794)
							(mid 0.249642 0.249642)
							(end 0.2794 0.1778)
						)
						(arc
							(start 0.2794 -0.1778)
							(mid 0.249642 -0.249642)
							(end 0.1778 -0.2794)
						)
					)
					(width 0)
					(fill yes)
				)
			)
		)
		(pad "2" smd custom
			(at 0 0.4445 90)
			(size 0.1397 0.1397)
			(layers "F.Cu" "F.Mask" "F.Paste")
			(net "TMP3_SCL")
			(options
				(clearance outline)
				(anchor circle)
			)
			(primitives
				(gr_poly
					(pts
						(arc
							(start -0.1778 -0.2794)
							(mid -0.249642 -0.249642)
							(end -0.2794 -0.1778)
						)
						(arc
							(start -0.2794 0.1778)
							(mid -0.249642 0.249642)
							(end -0.1778 0.2794)
						)
						(arc
							(start 0.1778 0.2794)
							(mid 0.249642 0.249642)
							(end 0.2794 0.1778)
						)
						(arc
							(start 0.2794 -0.1778)
							(mid 0.249642 -0.249642)
							(end 0.1778 -0.2794)
						)
					)
					(width 0)
					(fill yes)
				)
			)
		)
	)
)
